# S9S_MB_2U (Grand Teton) — schematic netlist excerpt (pin names and nets, part order shuffled) for the footprints in the layout excerpt that follows; sources: Cadence DE-HDL packaged netlist, KiCad conversion of 03242023_DA0F0TMBIJ0_F0T_Motherboard_J_brd_V01_OCP.brd

C641  Q_CAP  0.1UF 25V 10% X7R  pkg 0402  page 154 : A = P3V3_AUX ; B = GND
C1707  Q_CAP  0.1UF 25V 10% X7R  pkg 0402  page 234 : A = P3V3_AUX ; B = GND

(kicad_pcb
	(version 20260206)
	(generator "pcbnew")
	(generator_version "10.0")
	(general
		(thickness 1.6)
		(legacy_teardrops no)
	)
	(paper "A4")
	(title_block
		(title "03242023_DA0F0TMBIJ0_F0T_Motherboard_J_brd_V01_OCP.brd")
		(comment 1 "Grand Teton / footprints 738-739 of 6105")
	)
	(layers
		(0 "F.Cu" signal "TOP")
		(4 "In1.Cu" signal "GND")
		(6 "In2.Cu" signal "IN1")
		(8 "In3.Cu" signal "GND1")
		(10 "In4.Cu" signal "IN2")
		(12 "In5.Cu" signal "GND2")
		(14 "In6.Cu" signal "IN3")
		(16 "In7.Cu" signal "GND3")
		(18 "In8.Cu" signal "VCC")
		(20 "In9.Cu" signal "VCC1")
		(22 "In10.Cu" signal "GND4")
		(24 "In11.Cu" signal "IN4")
		(26 "In12.Cu" signal "GND5")
		(28 "In13.Cu" signal "IN5")
		(30 "In14.Cu" signal "GND6")
		(32 "In15.Cu" signal "IN6")
		(34 "In16.Cu" signal "GND7")
		(2 "B.Cu" signal "BOTTOM")
		(9 "F.Adhes" user "F.Adhesive")
		(11 "B.Adhes" user "B.Adhesive")
		(13 "F.Paste" user "Package Geometry/Pastemask Top")
		(15 "B.Paste" user "Package Geometry/Pastemask Bottom")
		(5 "F.SilkS" user "Ref Des/Silkscreen Top")
		(7 "B.SilkS" user "Ref Des/Silkscreen Bottom")
		(1 "F.Mask" user "Board Geometry/Soldermask Top")
		(3 "B.Mask" user "Board Geometry/Soldermask Bottom")
		(17 "Dwgs.User" user "User.Drawings")
		(19 "Cmts.User" user "User.Comments")
		(21 "Eco1.User" user "User.Eco1")
		(23 "Eco2.User" user "User.Eco2")
		(25 "Edge.Cuts" user "Board Geometry/Outline")
		(27 "Margin" user)
		(31 "F.CrtYd" user "Package Geometry/Place Bound Top")
		(29 "B.CrtYd" user "Package Geometry/Place Bound Bottom")
		(35 "F.Fab" user "Ref Des/Assembly Top")
		(33 "B.Fab" user "Ref Des/Assembly Bottom")
	)
	(footprint ""
		(layer "F.Cu")
		(at 214.692738 -68.846446 180)
		(property "Reference" "C641"
			(at 0 0 180)
			(layer "F.SilkS")
			(hide yes)
			(effects
				(font
					(size 1.27 1.27)
				)
			)
		)
		(property "Value" ""
			(at 0 0 180)
			(layer "F.Fab")
			(effects
				(font
					(size 1.27 1.27)
				)
			)
		)
		(duplicate_pad_numbers_are_jumpers no)
		(fp_line
			(start 0.7874 0.4064)
			(end -0.7874 0.4064)
			(stroke
				(width 0.1524)
				(type default)
			)
			(layer "F.SilkS")
		)
		(fp_line
			(start 0.7874 -0.4064)
			(end 0.7874 0.4064)
			(stroke
				(width 0.1524)
				(type default)
			)
			(layer "F.SilkS")
		)
		(fp_line
			(start -0.7874 0.4064)
			(end -0.7874 -0.4064)
			(stroke
				(width 0.1524)
				(type default)
			)
			(layer "F.SilkS")
		)
		(fp_line
			(start -0.7874 -0.4064)
			(end 0.7874 -0.4064)
			(stroke
				(width 0.1524)
				(type default)
			)
			(layer "F.SilkS")
		)
		(fp_line
			(start 0.67945 0.3048)
			(end 0.120396 0.3048)
			(stroke
				(width 0.1)
				(type default)
			)
			(layer "F.Fab")
		)
		(fp_line
			(start 0.67945 -0.3048)
			(end 0.67945 0.3048)
			(stroke
				(width 0.1)
				(type default)
			)
			(layer "F.Fab")
		)
		(fp_line
			(start 0.12065 -0.2794)
			(end 0.12065 -0.3048)
			(stroke
				(width 0.1)
				(type default)
			)
			(layer "F.Fab")
		)
		(fp_line
			(start 0.12065 -0.3048)
			(end 0.67945 -0.3048)
			(stroke
				(width 0.1)
				(type default)
			)
			(layer "F.Fab")
		)
		(fp_line
			(start 0.120396 0.3048)
			(end 0.120396 0.2794)
			(stroke
				(width 0.1)
				(type default)
			)
			(layer "F.Fab")
		)
		(fp_line
			(start 0.120396 0.2794)
			(end -0.12065 0.2794)
			(stroke
				(width 0.1)
				(type default)
			)
			(layer "F.Fab")
		)
		(fp_line
			(start -0.12065 0.3048)
			(end -0.67945 0.3048)
			(stroke
				(width 0.1)
				(type default)
			)
			(layer "F.Fab")
		)
		(fp_line
			(start -0.12065 0.2794)
			(end -0.12065 0.3048)
			(stroke
				(width 0.1)
				(type default)
			)
			(layer "F.Fab")
		)
		(fp_line
			(start -0.12065 -0.2794)
			(end 0.12065 -0.2794)
			(stroke
				(width 0.1)
				(type default)
			)
			(layer "F.Fab")
		)
		(fp_line
			(start -0.12065 -0.305054)
			(end -0.12065 -0.2794)
			(stroke
				(width 0.1)
				(type default)
			)
			(layer "F.Fab")
		)
		(fp_line
			(start -0.67945 0.3048)
			(end -0.67945 -0.305054)
			(stroke
				(width 0.1)
				(type default)
			)
			(layer "F.Fab")
		)
		(fp_line
			(start -0.67945 -0.305054)
			(end -0.12065 -0.305054)
			(stroke
				(width 0.1)
				(type default)
			)
			(layer "F.Fab")
		)
		(pad "1" smd circle
			(at -0.40005 0 180)
			(size 0 0)
			(layers "F.Cu" "F.Mask" "F.Paste")
			(net "P3V3_AUX")
		)
		(pad "2" smd circle
			(at 0.40005 0 180)
			(size 0 0)
			(layers "F.Cu" "F.Mask" "F.Paste")
			(net "GND")
		)
	)
	(footprint ""
		(layer "F.Cu")
		(at 166.17315 -421.435276 -90)
		(property "Reference" "C1707"
			(at 0 0 270)
			(layer "F.SilkS")
			(hide yes)
			(effects
				(font
					(size 1.27 1.27)
				)
			)
		)
		(property "Value" ""
			(at 0 0 270)
			(layer "F.Fab")
			(effects
				(font
					(size 1.27 1.27)
				)
			)
		)
		(duplicate_pad_numbers_are_jumpers no)
		(fp_line
			(start -0.7874 0.4064)
			(end -0.7874 -0.4064)
			(stroke
				(width 0.1524)
				(type default)
			)
			(layer "F.SilkS")
		)
		(fp_line
			(start 0.7874 0.4064)
			(end -0.7874 0.4064)
			(stroke
				(width 0.1524)
				(type default)
			)
			(layer "F.SilkS")
		)
		(fp_line
			(start -0.7874 -0.4064)
			(end 0.7874 -0.4064)
			(stroke
				(width 0.1524)
				(type default)
			)
			(layer "F.SilkS")
		)
		(fp_line
			(start 0.7874 -0.4064)
			(end 0.7874 0.4064)
			(stroke
				(width 0.1524)
				(type default)
			)
			(layer "F.SilkS")
		)
		(fp_line
			(start -0.67945 0.3048)
			(end -0.67945 -0.305054)
			(stroke
				(width 0.1)
				(type default)
			)
			(layer "F.Fab")
		)
		(fp_line
			(start -0.12065 0.3048)
			(end -0.67945 0.3048)
			(stroke
				(width 0.1)
				(type default)
			)
			(layer "F.Fab")
		)
		(fp_line
			(start 0.120396 0.3048)
			(end 0.120396 0.2794)
			(stroke
				(width 0.1)
				(type default)
			)
			(layer "F.Fab")
		)
		(fp_line
			(start 0.67945 0.3048)
			(end 0.120396 0.3048)
			(stroke
				(width 0.1)
				(type default)
			)
			(layer "F.Fab")
		)
		(fp_line
			(start -0.12065 0.2794)
			(end -0.12065 0.3048)
			(stroke
				(width 0.1)
				(type default)
			)
			(layer "F.Fab")
		)
		(fp_line
			(start 0.120396 0.2794)
			(end -0.12065 0.2794)
			(stroke
				(width 0.1)
				(type default)
			)
			(layer "F.Fab")
		)
		(fp_line
			(start -0.12065 -0.2794)
			(end 0.12065 -0.2794)
			(stroke
				(width 0.1)
				(type default)
			)
			(layer "F.Fab")
		)
		(fp_line
			(start 0.12065 -0.2794)
			(end 0.12065 -0.3048)
			(stroke
				(width 0.1)
				(type default)
			)
			(layer "F.Fab")
		)
		(fp_line
			(start 0.12065 -0.3048)
			(end 0.67945 -0.3048)
			(stroke
				(width 0.1)
				(type default)
			)
			(layer "F.Fab")
		)
		(fp_line
			(start 0.67945 -0.3048)
			(end 0.67945 0.3048)
			(stroke
				(width 0.1)
				(type default)
			)
			(layer "F.Fab")
		)
		(fp_line
			(start -0.67945 -0.305054)
			(end -0.12065 -0.305054)
			(stroke
				(width 0.1)
				(type default)
			)
			(layer "F.Fab")
		)
		(fp_line
			(start -0.12065 -0.305054)
			(end -0.12065 -0.2794)
			(stroke
				(width 0.1)
				(type default)
			)
			(layer "F.Fab")
		)
		(pad "1" smd circle
			(at -0.40005 0 270)
			(size 0 0)
			(layers "F.Cu" "F.Mask" "F.Paste")
			(net "P3V3_AUX")
		)
		(pad "2" smd circle
			(at 0.40005 0 270)
			(size 0 0)
			(layers "F.Cu" "F.Mask" "F.Paste")
			(net "GND")
		)
	)
)
